# TIMECARD (Time Appliance Project (Time Card)) — schematic netlist excerpt (pin names and nets, part order shuffled) for the footprints in the layout excerpt that follows; sources: Cadence DE-HDL packaged netlist, KiCad conversion of R4006-B0001-02_R01.brd

R265  RESISTOR  100KOHM 1%  pkg SMC_0402R_H016  page 21 : \1\ = XP3R3V_FPGA ; \2\ = UART_MAC_TX_FPGA_RX
R201  RESISTOR  4.7KOHM 1%  pkg SMC_0402R_H016  page 10 : \1\ = UNNAMED_127_MT25QL128ABA1ESES_3 ; \2\ = XP3R3V_FPGA

(kicad_pcb
	(version 20260206)
	(generator "pcbnew")
	(generator_version "10.0")
	(general
		(thickness 1.6)
		(legacy_teardrops no)
	)
	(paper "A4")
	(title_block
		(title "timecard-production-celestica-r4006 — R4006-B0001-02_R01.brd")
		(comment 1 "Time Appliance Project (Time Card) / footprints 1073-1074 of 1113")
	)
	(layers
		(0 "F.Cu" signal "TOP")
		(4 "In1.Cu" signal "L02_GND1")
		(6 "In2.Cu" signal "L03_SIG1")
		(8 "In3.Cu" signal "L04_GND2")
		(10 "In4.Cu" signal "L05_VCC1")
		(12 "In5.Cu" signal "L06_VCC2")
		(14 "In6.Cu" signal "L07_GND3")
		(16 "In7.Cu" signal "L08_SIG2")
		(18 "In8.Cu" signal "L09_GND4")
		(2 "B.Cu" signal "BOTTOM")
		(9 "F.Adhes" user "F.Adhesive")
		(11 "B.Adhes" user "B.Adhesive")
		(13 "F.Paste" user "Package Geometry/Pastemask Top")
		(15 "B.Paste" user "Package Geometry/Pastemask Bottom")
		(5 "F.SilkS" user "Ref Des/Silkscreen Top")
		(7 "B.SilkS" user "Ref Des/Silkscreen Bottom")
		(1 "F.Mask" user "Board Geometry/Soldermask Top")
		(3 "B.Mask" user "Board Geometry/Soldermask Bottom")
		(17 "Dwgs.User" user "User.Drawings")
		(19 "Cmts.User" user "User.Comments")
		(21 "Eco1.User" user "User.Eco1")
		(23 "Eco2.User" user "User.Eco2")
		(25 "Edge.Cuts" user "Board Geometry/Outline")
		(27 "Margin" user)
		(31 "F.CrtYd" user "Package Geometry/Place Bound Top")
		(29 "B.CrtYd" user "Package Geometry/Place Bound Bottom")
		(35 "F.Fab" user "Ref Des/Assembly Top")
		(33 "B.Fab" user "Ref Des/Assembly Bottom")
	)
	(footprint ""
		(layer "B.Cu")
		(at 95.631 -85.598)
		(property "Reference" "R201"
			(at -0.254 -5.54863 0)
			(unlocked yes)
			(layer "B.SilkS")
			(effects
				(font
					(size 0.7874 0.5842)
					(thickness 0.1524)
				)
				(justify mirror)
			)
		)
		(property "Value" "VAL*"
			(at -0.02032 2.13233 0)
			(unlocked yes)
			(layer "B.Fab")
			(hide yes)
			(effects
				(font
					(size 0.7874 0.5842)
					(thickness 0.1524)
				)
				(justify mirror)
			)
		)
		(property "Tolerance" "TOL*"
			(at -0.044704 3.05435 0)
			(unlocked yes)
			(layer "Cmts.User")
			(hide yes)
			(effects
				(font
					(size 0.7874 0.5842)
					(thickness 0.1524)
				)
				(justify mirror)
			)
		)
		(property "User Part Number" "PARTNUM*"
			(at -0.02032 4.024884 0)
			(unlocked yes)
			(layer "Cmts.User")
			(hide yes)
			(effects
				(font
					(size 0.7874 0.5842)
					(thickness 0.1524)
				)
				(justify mirror)
			)
		)
		(property "Device Type" "RESISTOR-G155-14701-01,4.7KOHMA"
			(at -0.008382 1.210564 0)
			(unlocked yes)
			(layer "B.Fab")
			(hide yes)
			(effects
				(font
					(size 0.7874 0.5842)
					(thickness 0.1524)
				)
				(justify mirror)
			)
		)
		(duplicate_pad_numbers_are_jumpers no)
		(fp_line
			(start -1.143 -0.5588)
			(end 1.143 -0.5588)
			(stroke
				(width 0.1)
				(type default)
			)
			(layer "B.SilkS")
		)
		(fp_line
			(start -1.143 0.5588)
			(end -1.143 -0.5588)
			(stroke
				(width 0.1)
				(type default)
			)
			(layer "B.SilkS")
		)
		(fp_line
			(start 1.143 -0.5588)
			(end 1.143 0.5588)
			(stroke
				(width 0.1)
				(type default)
			)
			(layer "B.SilkS")
		)
		(fp_line
			(start 1.143 0.5588)
			(end -1.143 0.5588)
			(stroke
				(width 0.1)
				(type default)
			)
			(layer "B.SilkS")
		)
		(fp_rect
			(start -1.143 0.5588)
			(end 1.143 -0.5588)
			(stroke
				(width 0)
				(type default)
			)
			(fill no)
			(layer "B.CrtYd")
		)
		(fp_line
			(start -0.508 -0.3048)
			(end 0.508 -0.3048)
			(stroke
				(width 0.1)
				(type default)
			)
			(layer "B.Fab")
		)
		(fp_line
			(start -0.508 0.3048)
			(end -0.508 -0.3048)
			(stroke
				(width 0.1)
				(type default)
			)
			(layer "B.Fab")
		)
		(fp_line
			(start 0.508 -0.3048)
			(end 0.508 0.3048)
			(stroke
				(width 0.1)
				(type default)
			)
			(layer "B.Fab")
		)
		(fp_line
			(start 0.508 0.3048)
			(end -0.508 0.3048)
			(stroke
				(width 0.1)
				(type default)
			)
			(layer "B.Fab")
		)
		(pad "1" smd rect
			(at 0.5334 0 180)
			(size 0.7112 0.6096)
			(layers "B.Cu" "B.Mask" "B.Paste")
			(net "UNNAMED_127_MT25QL128ABA1ESES_3")
		)
		(pad "2" smd rect
			(at -0.5334 0 180)
			(size 0.7112 0.6096)
			(layers "B.Cu" "B.Mask" "B.Paste")
			(net "XP3R3V_FPGA")
		)
		(zone
			(layer "B.Cu")
			(hatch none 0.5)
			(connect_pads
				(clearance 0)
			)
			(min_thickness 0.25)
			(keepout
				(tracks allowed)
				(vias not_allowed)
				(pads allowed)
				(copperpour not_allowed)
				(footprints allowed)
			)
			(placement
				(enabled no)
				(sheetname "")
			)
			(fill
				(thermal_gap 0.5)
				(thermal_bridge_width 0.5)
				(island_removal_mode 0)
			)
			(polygon
				(pts
					(xy 95.5548 -85.2932) (xy 95.7072 -85.2932) (xy 95.7072 -85.9028) (xy 95.5548 -85.9028)
				)
			)
		)
	)
	(footprint ""
		(layer "B.Cu")
		(at 124.587 -50.165)
		(property "Reference" "R265"
			(at 3.302 0.03937 0)
			(unlocked yes)
			(layer "B.SilkS")
			(effects
				(font
					(size 0.7874 0.5842)
					(thickness 0.1524)
				)
				(justify mirror)
			)
		)
		(property "Value" "VAL*"
			(at -0.02032 2.13233 0)
			(unlocked yes)
			(layer "B.Fab")
			(hide yes)
			(effects
				(font
					(size 0.7874 0.5842)
					(thickness 0.1524)
				)
				(justify mirror)
			)
		)
		(property "Device Type" "RESISTOR-G155-11003-01,100KOHMA"
			(at -0.008382 1.210564 0)
			(unlocked yes)
			(layer "B.Fab")
			(hide yes)
			(effects
				(font
					(size 0.7874 0.5842)
					(thickness 0.1524)
				)
				(justify mirror)
			)
		)
		(property "User Part Number" "PARTNUM*"
			(at -0.02032 4.024884 0)
			(unlocked yes)
			(layer "Cmts.User")
			(hide yes)
			(effects
				(font
					(size 0.7874 0.5842)
					(thickness 0.1524)
				)
				(justify mirror)
			)
		)
		(property "Tolerance" "TOL*"
			(at -0.044704 3.05435 0)
			(unlocked yes)
			(layer "Cmts.User")
			(hide yes)
			(effects
				(font
					(size 0.7874 0.5842)
					(thickness 0.1524)
				)
				(justify mirror)
			)
		)
		(duplicate_pad_numbers_are_jumpers no)
		(fp_line
			(start -1.143 -0.5588)
			(end 1.143 -0.5588)
			(stroke
				(width 0.1)
				(type default)
			)
			(layer "B.SilkS")
		)
		(fp_line
			(start -1.143 0.5588)
			(end -1.143 -0.5588)
			(stroke
				(width 0.1)
				(type default)
			)
			(layer "B.SilkS")
		)
		(fp_line
			(start 1.143 -0.5588)
			(end 1.143 0.5588)
			(stroke
				(width 0.1)
				(type default)
			)
			(layer "B.SilkS")
		)
		(fp_line
			(start 1.143 0.5588)
			(end -1.143 0.5588)
			(stroke
				(width 0.1)
				(type default)
			)
			(layer "B.SilkS")
		)
		(fp_rect
			(start -1.143 -0.5588)
			(end 1.143 0.5588)
			(stroke
				(width 0)
				(type default)
			)
			(fill no)
			(layer "B.CrtYd")
		)
		(fp_line
			(start -0.508 -0.3048)
			(end 0.508 -0.3048)
			(stroke
				(width 0.1)
				(type default)
			)
			(layer "B.Fab")
		)
		(fp_line
			(start -0.508 0.3048)
			(end -0.508 -0.3048)
			(stroke
				(width 0.1)
				(type default)
			)
			(layer "B.Fab")
		)
		(fp_line
			(start 0.508 -0.3048)
			(end 0.508 0.3048)
			(stroke
				(width 0.1)
				(type default)
			)
			(layer "B.Fab")
		)
		(fp_line
			(start 0.508 0.3048)
			(end -0.508 0.3048)
			(stroke
				(width 0.1)
				(type default)
			)
			(layer "B.Fab")
		)
		(pad "1" smd rect
			(at 0.5334 0 180)
			(size 0.7112 0.6096)
			(layers "B.Cu" "B.Mask" "B.Paste")
			(net "XP3R3V_FPGA")
		)
		(pad "2" smd rect
			(at -0.5334 0 180)
			(size 0.7112 0.6096)
			(layers "B.Cu" "B.Mask" "B.Paste")
			(net "UART_MAC_TX_FPGA_RX")
		)
		(zone
			(layer "B.Cu")
			(hatch none 0.5)
			(connect_pads
				(clearance 0)
			)
			(min_thickness 0.25)
			(keepout
				(tracks allowed)
				(vias not_allowed)
				(pads allowed)
				(copperpour not_allowed)
				(footprints allowed)
			)
			(placement
				(enabled no)
				(sheetname "")
			)
			(fill
				(thermal_gap 0.5)
				(thermal_bridge_width 0.5)
				(island_removal_mode 0)
			)
			(polygon
				(pts
					(xy 124.5108 -50.4698) (xy 124.5108 -49.8602) (xy 124.6632 -49.8602) (xy 124.6632 -50.4698)
				)
			)
		)
		(zone
			(layer "B.Cu")
			(hatch none 0.5)
			(connect_pads
				(clearance 0)
			)
			(min_thickness 0.25)
			(keepout
				(tracks not_allowed)
				(vias allowed)
				(pads allowed)
				(copperpour not_allowed)
				(footprints allowed)
			)
			(placement
				(enabled no)
				(sheetname "")
			)
			(fill
				(thermal_gap 0.5)
				(thermal_bridge_width 0.5)
				(island_removal_mode 0)
			)
			(polygon
				(pts
					(xy 124.5108 -50.4698) (xy 124.5108 -49.8602) (xy 124.6632 -49.8602) (xy 124.6632 -50.4698)
				)
			)
		)
	)
)
